(kicad_pcb
	(version 20260206)
	(generator "pcbnew")
	(generator_version "10.0")
	(general
		(thickness 1.6)
		(legacy_teardrops no)
	)
	(paper "A4")
	(title_block
		(title "04192023_DAF0TMB3IC0_F0TG_MB_C_brd_V02_OCP.brd")
		(comment 1 "Grand Teton / footprints 4196-4203 of 8354")
	)
	(layers
		(0 "F.Cu" signal "TOP")
		(4 "In1.Cu" signal "GND")
		(6 "In2.Cu" signal "IN1")
		(8 "In3.Cu" signal "GND1")
		(10 "In4.Cu" signal "IN2")
		(12 "In5.Cu" signal "GND2")
		(14 "In6.Cu" signal "IN3")
		(16 "In7.Cu" signal "GND3")
		(18 "In8.Cu" signal "VCC")
		(20 "In9.Cu" signal "VCC1")
		(22 "In10.Cu" signal "GND4")
		(24 "In11.Cu" signal "IN4")
		(26 "In12.Cu" signal "GND5")
		(28 "In13.Cu" signal "IN5")
		(30 "In14.Cu" signal "GND6")
		(32 "In15.Cu" signal "IN6")
		(34 "In16.Cu" signal "GND7")
		(2 "B.Cu" signal "BOTTOM")
		(9 "F.Adhes" user "F.Adhesive")
		(11 "B.Adhes" user "B.Adhesive")
		(13 "F.Paste" user "Package Geometry/Pastemask Top")
		(15 "B.Paste" user "Package Geometry/Pastemask Bottom")
		(5 "F.SilkS" user "Ref Des/Silkscreen Top")
		(7 "B.SilkS" user "Ref Des/Silkscreen Bottom")
		(1 "F.Mask" user "Board Geometry/Soldermask Top")
		(3 "B.Mask" user "Board Geometry/Soldermask Bottom")
		(17 "Dwgs.User" user "User.Drawings")
		(19 "Cmts.User" user "User.Comments")
		(21 "Eco1.User" user "User.Eco1")
		(23 "Eco2.User" user "User.Eco2")
		(25 "Edge.Cuts" user "Board Geometry/Outline")
		(27 "Margin" user)
		(31 "F.CrtYd" user "Package Geometry/Place Bound Top")
		(29 "B.CrtYd" user "Package Geometry/Place Bound Bottom")
		(35 "F.Fab" user "Ref Des/Assembly Top")
		(33 "B.Fab" user "Ref Des/Assembly Bottom")
	)
	(footprint ""
		(layer "F.Cu")
		(at 98.380296 -425.82973 -90)
		(property "Reference" "R4202"
			(at 0 0 270)
			(layer "F.SilkS")
			(hide yes)
			(effects
				(font
					(size 1.27 1.27)
				)
			)
		)
		(property "Value" ""
			(at 0 0 270)
			(layer "F.Fab")
			(effects
				(font
					(size 1.27 1.27)
				)
			)
		)
		(duplicate_pad_numbers_are_jumpers no)
		(fp_line
			(start -0.7874 0.4064)
			(end -0.7874 -0.4064)
			(stroke
				(width 0.1524)
				(type default)
			)
			(layer "F.SilkS")
		)
		(fp_line
			(start 0.7874 0.4064)
			(end -0.7874 0.4064)
			(stroke
				(width 0.1524)
				(type default)
			)
			(layer "F.SilkS")
		)
		(fp_line
			(start -0.7874 -0.4064)
			(end 0.7874 -0.4064)
			(stroke
				(width 0.1524)
				(type default)
			)
			(layer "F.SilkS")
		)
		(fp_line
			(start 0.7874 -0.4064)
			(end 0.7874 0.4064)
			(stroke
				(width 0.1524)
				(type default)
			)
			(layer "F.SilkS")
		)
		(fp_line
			(start -0.67945 0.3048)
			(end -0.67945 -0.305054)
			(stroke
				(width 0.1)
				(type default)
			)
			(layer "F.Fab")
		)
		(fp_line
			(start -0.12065 0.3048)
			(end -0.67945 0.3048)
			(stroke
				(width 0.1)
				(type default)
			)
			(layer "F.Fab")
		)
		(fp_line
			(start 0.120396 0.3048)
			(end 0.120396 0.2794)
			(stroke
				(width 0.1)
				(type default)
			)
			(layer "F.Fab")
		)
		(fp_line
			(start 0.67945 0.3048)
			(end 0.120396 0.3048)
			(stroke
				(width 0.1)
				(type default)
			)
			(layer "F.Fab")
		)
		(fp_line
			(start -0.12065 0.2794)
			(end -0.12065 0.3048)
			(stroke
				(width 0.1)
				(type default)
			)
			(layer "F.Fab")
		)
		(fp_line
			(start 0.120396 0.2794)
			(end -0.12065 0.2794)
			(stroke
				(width 0.1)
				(type default)
			)
			(layer "F.Fab")
		)
		(fp_line
			(start -0.12065 -0.2794)
			(end 0.12065 -0.2794)
			(stroke
				(width 0.1)
				(type default)
			)
			(layer "F.Fab")
		)
		(fp_line
			(start 0.12065 -0.2794)
			(end 0.12065 -0.3048)
			(stroke
				(width 0.1)
				(type default)
			)
			(layer "F.Fab")
		)
		(fp_line
			(start 0.12065 -0.3048)
			(end 0.67945 -0.3048)
			(stroke
				(width 0.1)
				(type default)
			)
			(layer "F.Fab")
		)
		(fp_line
			(start 0.67945 -0.3048)
			(end 0.67945 0.3048)
			(stroke
				(width 0.1)
				(type default)
			)
			(layer "F.Fab")
		)
		(fp_line
			(start -0.67945 -0.305054)
			(end -0.12065 -0.305054)
			(stroke
				(width 0.1)
				(type default)
			)
			(layer "F.Fab")
		)
		(fp_line
			(start -0.12065 -0.305054)
			(end -0.12065 -0.2794)
			(stroke
				(width 0.1)
				(type default)
			)
			(layer "F.Fab")
		)
		(pad "1" smd circle
			(at -0.40005 0 270)
			(size 0 0)
			(layers "F.Cu" "F.Mask" "F.Paste")
			(net "P3V3_AUX")
		)
		(pad "2" smd circle
			(at 0.40005 0 270)
			(size 0 0)
			(layers "F.Cu" "F.Mask" "F.Paste")
			(net "U272_2_ADD0")
		)
	)
	(footprint ""
		(layer "F.Cu")
		(at 182.919878 -342.462358 -90)
		(property "Reference" "PL54"
			(at -15.116048 5.983986 0)
			(unlocked yes)
			(layer "F.SilkS")
			(effects
				(font
					(size 0.7874 0.5842)
					(thickness 0.1524)
				)
				(justify left)
			)
		)
		(property "Value" ""
			(at 0 0 270)
			(layer "F.Fab")
			(effects
				(font
					(size 1.27 1.27)
				)
			)
		)
		(duplicate_pad_numbers_are_jumpers no)
		(fp_line
			(start -4.99999 3.849878)
			(end -4.99999 2.23901)
			(stroke
				(width 0.1524)
				(type default)
			)
			(layer "F.SilkS")
		)
		(fp_line
			(start 4.99999 3.849878)
			(end -4.99999 3.849878)
			(stroke
				(width 0.1524)
				(type default)
			)
			(layer "F.SilkS")
		)
		(fp_line
			(start 4.99999 2.23901)
			(end 4.99999 3.849878)
			(stroke
				(width 0.1524)
				(type default)
			)
			(layer "F.SilkS")
		)
		(fp_line
			(start -4.99999 -2.23901)
			(end -4.99999 -3.849878)
			(stroke
				(width 0.1524)
				(type default)
			)
			(layer "F.SilkS")
		)
		(fp_line
			(start -4.99999 -3.849878)
			(end 4.99999 -3.849878)
			(stroke
				(width 0.1524)
				(type default)
			)
			(layer "F.SilkS")
		)
		(fp_line
			(start 4.99999 -3.849878)
			(end 4.99999 -2.23901)
			(stroke
				(width 0.1524)
				(type default)
			)
			(layer "F.SilkS")
		)
		(fp_line
			(start -4.99999 3.849878)
			(end -4.99999 -3.849878)
			(stroke
				(width 0.1)
				(type default)
			)
			(layer "F.Fab")
		)
		(fp_line
			(start 4.99999 3.849878)
			(end -4.99999 3.849878)
			(stroke
				(width 0.1)
				(type default)
			)
			(layer "F.Fab")
		)
		(fp_line
			(start -4.99999 -3.849878)
			(end 4.99999 -3.849878)
			(stroke
				(width 0.1)
				(type default)
			)
			(layer "F.Fab")
		)
		(fp_line
			(start 4.99999 -3.849878)
			(end 4.99999 3.849878)
			(stroke
				(width 0.1)
				(type default)
			)
			(layer "F.Fab")
		)
		(pad "1" smd rect
			(at -3.299968 0 270)
			(size 3.302 4.2164)
			(layers "F.Cu" "F.Mask" "F.Paste")
			(net "SW_PVDD11_S3_P1_SW1")
		)
		(pad "2" smd rect
			(at 3.299968 0 270)
			(size 3.302 4.2164)
			(layers "F.Cu" "F.Mask" "F.Paste")
			(net "PVDD11_S3_P1")
		)
	)
	(footprint ""
		(layer "F.Cu")
		(at 142.595092 -375.94286 180)
		(property "Reference" "C771"
			(at 0 0 180)
			(layer "F.SilkS")
			(hide yes)
			(effects
				(font
					(size 1.27 1.27)
				)
			)
		)
		(property "Value" ""
			(at 0 0 180)
			(layer "F.Fab")
			(effects
				(font
					(size 1.27 1.27)
				)
			)
		)
		(duplicate_pad_numbers_are_jumpers no)
		(fp_line
			(start 0.299974 0.150114)
			(end -0.299974 0.150114)
			(stroke
				(width 0.1)
				(type default)
			)
			(layer "F.Fab")
		)
		(fp_line
			(start 0.299974 -0.150114)
			(end 0.299974 0.150114)
			(stroke
				(width 0.1)
				(type default)
			)
			(layer "F.Fab")
		)
		(fp_line
			(start -0.299974 0.150114)
			(end -0.299974 -0.150114)
			(stroke
				(width 0.1)
				(type default)
			)
			(layer "F.Fab")
		)
		(fp_line
			(start -0.299974 -0.150114)
			(end 0.299974 -0.150114)
			(stroke
				(width 0.1)
				(type default)
			)
			(layer "F.Fab")
		)
		(pad "1" smd rect
			(at -0.2667 0 180)
			(size 0.3048 0.381)
			(layers "F.Cu" "F.Mask" "F.Paste")
			(net "P5E_CPU1_P2_TX_C_DP<1>")
		)
		(pad "2" smd rect
			(at 0.2667 0 180)
			(size 0.3048 0.381)
			(layers "F.Cu" "F.Mask" "F.Paste")
			(net "P5E_CPU1_P2_TX_DP<1>")
		)
	)
	(footprint ""
		(layer "F.Cu")
		(at 455.617834 -99.164394)
		(property "Reference" "R1719"
			(at 0 0 0)
			(layer "F.SilkS")
			(hide yes)
			(effects
				(font
					(size 1.27 1.27)
				)
			)
		)
		(property "Value" ""
			(at 0 0 0)
			(layer "F.Fab")
			(effects
				(font
					(size 1.27 1.27)
				)
			)
		)
		(duplicate_pad_numbers_are_jumpers no)
		(fp_line
			(start -0.7874 -0.4064)
			(end 0.7874 -0.4064)
			(stroke
				(width 0.1524)
				(type default)
			)
			(layer "F.SilkS")
		)
		(fp_line
			(start -0.7874 0.4064)
			(end -0.7874 -0.4064)
			(stroke
				(width 0.1524)
				(type default)
			)
			(layer "F.SilkS")
		)
		(fp_line
			(start 0.7874 -0.4064)
			(end 0.7874 0.4064)
			(stroke
				(width 0.1524)
				(type default)
			)
			(layer "F.SilkS")
		)
		(fp_line
			(start 0.7874 0.4064)
			(end -0.7874 0.4064)
			(stroke
				(width 0.1524)
				(type default)
			)
			(layer "F.SilkS")
		)
		(fp_line
			(start -0.67945 -0.305054)
			(end -0.12065 -0.305054)
			(stroke
				(width 0.1)
				(type default)
			)
			(layer "F.Fab")
		)
		(fp_line
			(start -0.67945 0.3048)
			(end -0.67945 -0.305054)
			(stroke
				(width 0.1)
				(type default)
			)
			(layer "F.Fab")
		)
		(fp_line
			(start -0.12065 -0.305054)
			(end -0.12065 -0.2794)
			(stroke
				(width 0.1)
				(type default)
			)
			(layer "F.Fab")
		)
		(fp_line
			(start -0.12065 -0.2794)
			(end 0.12065 -0.2794)
			(stroke
				(width 0.1)
				(type default)
			)
			(layer "F.Fab")
		)
		(fp_line
			(start -0.12065 0.2794)
			(end -0.12065 0.3048)
			(stroke
				(width 0.1)
				(type default)
			)
			(layer "F.Fab")
		)
		(fp_line
			(start -0.12065 0.3048)
			(end -0.67945 0.3048)
			(stroke
				(width 0.1)
				(type default)
			)
			(layer "F.Fab")
		)
		(fp_line
			(start 0.120396 0.2794)
			(end -0.12065 0.2794)
			(stroke
				(width 0.1)
				(type default)
			)
			(layer "F.Fab")
		)
		(fp_line
			(start 0.120396 0.3048)
			(end 0.120396 0.2794)
			(stroke
				(width 0.1)
				(type default)
			)
			(layer "F.Fab")
		)
		(fp_line
			(start 0.12065 -0.3048)
			(end 0.67945 -0.3048)
			(stroke
				(width 0.1)
				(type default)
			)
			(layer "F.Fab")
		)
		(fp_line
			(start 0.12065 -0.2794)
			(end 0.12065 -0.3048)
			(stroke
				(width 0.1)
				(type default)
			)
			(layer "F.Fab")
		)
		(fp_line
			(start 0.67945 -0.3048)
			(end 0.67945 0.3048)
			(stroke
				(width 0.1)
				(type default)
			)
			(layer "F.Fab")
		)
		(fp_line
			(start 0.67945 0.3048)
			(end 0.120396 0.3048)
			(stroke
				(width 0.1)
				(type default)
			)
			(layer "F.Fab")
		)
		(pad "1" smd circle
			(at -0.40005 0)
			(size 0 0)
			(layers "F.Cu" "F.Mask" "F.Paste")
			(net "OCP_SFF_AUX_PWR_EN")
		)
		(pad "2" smd circle
			(at 0.40005 0)
			(size 0 0)
			(layers "F.Cu" "F.Mask" "F.Paste")
			(net "OCP_SFF_AUX_PWR_EN_R1")
		)
	)
	(footprint ""
		(layer "F.Cu")
		(at 98.956114 -192.010284 180)
		(property "Reference" "PL31"
			(at -7.476744 3.583686 90)
			(unlocked yes)
			(layer "F.SilkS")
			(effects
				(font
					(size 0.7874 0.5842)
					(thickness 0.1524)
				)
				(justify left)
			)
		)
		(property "Value" ""
			(at 0 0 180)
			(layer "F.Fab")
			(effects
				(font
					(size 1.27 1.27)
				)
			)
		)
		(duplicate_pad_numbers_are_jumpers no)
		(fp_line
			(start 3.750056 5.500116)
			(end 3.750056 -5.500116)
			(stroke
				(width 0.1524)
				(type default)
			)
			(layer "F.SilkS")
		)
		(fp_line
			(start 3.750056 -5.500116)
			(end 2.393442 -5.500116)
			(stroke
				(width 0.1524)
				(type default)
			)
			(layer "F.SilkS")
		)
		(fp_line
			(start 2.393442 5.500116)
			(end 3.750056 5.500116)
			(stroke
				(width 0.1524)
				(type default)
			)
			(layer "F.SilkS")
		)
		(fp_line
			(start -2.393442 5.500116)
			(end -3.750056 5.500116)
			(stroke
				(width 0.1524)
				(type default)
			)
			(layer "F.SilkS")
		)
		(fp_line
			(start -3.750056 5.500116)
			(end -3.750056 -5.500116)
			(stroke
				(width 0.1524)
				(type default)
			)
			(layer "F.SilkS")
		)
		(fp_line
			(start -3.750056 -5.500116)
			(end -2.393442 -5.500116)
			(stroke
				(width 0.1524)
				(type default)
			)
			(layer "F.SilkS")
		)
		(fp_poly
			(pts
				(xy -3.9116 -4.249928) (xy -4.9276 -3.741928) (xy -4.9276 -4.757928)
			)
			(stroke
				(width 0)
				(type default)
			)
			(fill yes)
			(layer "F.SilkS")
		)
		(fp_line
			(start 3.750056 5.500116)
			(end 3.750056 -5.500116)
			(stroke
				(width 0.1)
				(type default)
			)
			(layer "F.Fab")
		)
		(fp_line
			(start 3.750056 -5.500116)
			(end -3.750056 -5.500116)
			(stroke
				(width 0.1)
				(type default)
			)
			(layer "F.Fab")
		)
		(fp_line
			(start -3.750056 5.500116)
			(end 3.750056 5.500116)
			(stroke
				(width 0.1)
				(type default)
			)
			(layer "F.Fab")
		)
		(fp_line
			(start -3.750056 -5.500116)
			(end -3.750056 5.500116)
			(stroke
				(width 0.1)
				(type default)
			)
			(layer "F.Fab")
		)
		(fp_poly
			(pts
				(xy -4.9276 -4.757928) (xy -4.9276 -3.741928) (xy -3.9116 -4.249928)
			)
			(stroke
				(width 0)
				(type default)
			)
			(fill yes)
			(layer "F.Fab")
		)
		(pad "1" smd rect
			(at 0 -4.249928 90)
			(size 2.413 4.5212)
			(layers "F.Cu" "F.Mask" "F.Paste")
			(net "SW_PVDDCR_CPU0_P1_SW3")
		)
		(pad "2" smd rect
			(at 0 -1.175004 90)
			(size 1.3716 4.5212)
			(layers "F.Cu" "F.Mask" "F.Paste")
			(net "IND_CPU0_P1_CPL2")
		)
		(pad "3" smd rect
			(at 0 1.175004 90)
			(size 1.3716 4.5212)
			(layers "F.Cu" "F.Mask" "F.Paste")
			(net "IND_CPU0_P1_CPL3")
		)
		(pad "4" smd rect
			(at 0 4.249928 90)
			(size 2.413 4.5212)
			(layers "F.Cu" "F.Mask" "F.Paste")
			(net "PVDDCR_CPU0_P1")
		)
	)
	(footprint ""
		(layer "F.Cu")
		(at 436.052722 -408.01036)
		(property "Reference" "R1400"
			(at 0 0 0)
			(layer "F.SilkS")
			(hide yes)
			(effects
				(font
					(size 1.27 1.27)
				)
			)
		)
		(property "Value" ""
			(at 0 0 0)
			(layer "F.Fab")
			(effects
				(font
					(size 1.27 1.27)
				)
			)
		)
		(duplicate_pad_numbers_are_jumpers no)
		(fp_line
			(start -0.32512 -0.175006)
			(end 0.32512 -0.175006)
			(stroke
				(width 0.1)
				(type default)
			)
			(layer "F.Fab")
		)
		(fp_line
			(start -0.32512 0.175006)
			(end -0.32512 -0.175006)
			(stroke
				(width 0.1)
				(type default)
			)
			(layer "F.Fab")
		)
		(fp_line
			(start 0.32512 -0.175006)
			(end 0.32512 0.175006)
			(stroke
				(width 0.1)
				(type default)
			)
			(layer "F.Fab")
		)
		(fp_line
			(start 0.32512 0.175006)
			(end -0.32512 0.175006)
			(stroke
				(width 0.1)
				(type default)
			)
			(layer "F.Fab")
		)
		(pad "1" smd rect
			(at -0.2667 0)
			(size 0.3048 0.381)
			(layers "F.Cu" "F.Mask" "F.Paste")
			(net "JTAG_TRST_RT_CPU0_P2_N")
		)
		(pad "2" smd rect
			(at 0.2667 0 180)
			(size 0.3048 0.381)
			(layers "F.Cu" "F.Mask" "F.Paste")
			(net "GND")
		)
	)
	(footprint ""
		(layer "F.Cu")
		(at 11.421618 -105.48239 90)
		(property "Reference" "R2786"
			(at 0 0 90)
			(layer "F.SilkS")
			(hide yes)
			(effects
				(font
					(size 1.27 1.27)
				)
			)
		)
		(property "Value" ""
			(at 0 0 90)
			(layer "F.Fab")
			(effects
				(font
					(size 1.27 1.27)
				)
			)
		)
		(duplicate_pad_numbers_are_jumpers no)
		(fp_line
			(start 0.7874 -0.4064)
			(end 0.7874 0.4064)
			(stroke
				(width 0.1524)
				(type default)
			)
			(layer "F.SilkS")
		)
		(fp_line
			(start -0.7874 -0.4064)
			(end 0.7874 -0.4064)
			(stroke
				(width 0.1524)
				(type default)
			)
			(layer "F.SilkS")
		)
		(fp_line
			(start 0.7874 0.4064)
			(end -0.7874 0.4064)
			(stroke
				(width 0.1524)
				(type default)
			)
			(layer "F.SilkS")
		)
		(fp_line
			(start -0.7874 0.4064)
			(end -0.7874 -0.4064)
			(stroke
				(width 0.1524)
				(type default)
			)
			(layer "F.SilkS")
		)
		(fp_line
			(start -0.12065 -0.305054)
			(end -0.12065 -0.2794)
			(stroke
				(width 0.1)
				(type default)
			)
			(layer "F.Fab")
		)
		(fp_line
			(start -0.67945 -0.305054)
			(end -0.12065 -0.305054)
			(stroke
				(width 0.1)
				(type default)
			)
			(layer "F.Fab")
		)
		(fp_line
			(start 0.67945 -0.3048)
			(end 0.67945 0.3048)
			(stroke
				(width 0.1)
				(type default)
			)
			(layer "F.Fab")
		)
		(fp_line
			(start 0.12065 -0.3048)
			(end 0.67945 -0.3048)
			(stroke
				(width 0.1)
				(type default)
			)
			(layer "F.Fab")
		)
		(fp_line
			(start 0.12065 -0.2794)
			(end 0.12065 -0.3048)
			(stroke
				(width 0.1)
				(type default)
			)
			(layer "F.Fab")
		)
		(fp_line
			(start -0.12065 -0.2794)
			(end 0.12065 -0.2794)
			(stroke
				(width 0.1)
				(type default)
			)
			(layer "F.Fab")
		)
		(fp_line
			(start 0.120396 0.2794)
			(end -0.12065 0.2794)
			(stroke
				(width 0.1)
				(type default)
			)
			(layer "F.Fab")
		)
		(fp_line
			(start -0.12065 0.2794)
			(end -0.12065 0.3048)
			(stroke
				(width 0.1)
				(type default)
			)
			(layer "F.Fab")
		)
		(fp_line
			(start 0.67945 0.3048)
			(end 0.120396 0.3048)
			(stroke
				(width 0.1)
				(type default)
			)
			(layer "F.Fab")
		)
		(fp_line
			(start 0.120396 0.3048)
			(end 0.120396 0.2794)
			(stroke
				(width 0.1)
				(type default)
			)
			(layer "F.Fab")
		)
		(fp_line
			(start -0.12065 0.3048)
			(end -0.67945 0.3048)
			(stroke
				(width 0.1)
				(type default)
			)
			(layer "F.Fab")
		)
		(fp_line
			(start -0.67945 0.3048)
			(end -0.67945 -0.305054)
			(stroke
				(width 0.1)
				(type default)
			)
			(layer "F.Fab")
		)
		(pad "1" smd rect
			(at -0.40005 0 270)
			(size 0.4572 0.508)
			(layers "F.Cu" "F.Mask" "F.Paste")
			(net "USB2_HUB_SWB_DP")
		)
		(pad "2" smd rect
			(at 0.40005 0 270)
			(size 0.4572 0.508)
			(layers "F.Cu" "F.Mask" "F.Paste")
			(net "USB2_HUB_BUF_SWB_R_DP")
		)
	)
	(footprint ""
		(layer "F.Cu")
		(at 116.332 -125.349)
		(property "Reference" "U6006"
			(at -1.979676 -2.710942 0)
			(unlocked yes)
			(layer "F.SilkS")
			(effects
				(font
					(size 0.7874 0.5842)
					(thickness 0.1524)
				)
				(justify left)
			)
		)
		(property "Value" ""
			(at 0 0 0)
			(layer "F.Fab")
			(effects
				(font
					(size 1.27 1.27)
				)
			)
		)
		(duplicate_pad_numbers_are_jumpers no)
		(fp_line
			(start -1.759712 -1.500124)
			(end 1.759712 -1.500124)
			(stroke
				(width 0.1524)
				(type default)
			)
			(layer "F.SilkS")
		)
		(fp_line
			(start -1.759712 1.500124)
			(end -1.759712 -1.500124)
			(stroke
				(width 0.1524)
				(type default)
			)
			(layer "F.SilkS")
		)
		(fp_line
			(start 1.759712 -1.500124)
			(end 1.759712 1.500124)
			(stroke
				(width 0.1524)
				(type default)
			)
			(layer "F.SilkS")
		)
		(fp_line
			(start 1.759712 1.500124)
			(end -1.759712 1.500124)
			(stroke
				(width 0.1524)
				(type default)
			)
			(layer "F.SilkS")
		)
		(fp_line
			(start -0.700024 -1.500124)
			(end 0.700024 -1.500124)
			(stroke
				(width 0.1)
				(type default)
			)
			(layer "F.Fab")
		)
		(fp_line
			(start -0.700024 1.500124)
			(end -0.700024 -1.500124)
			(stroke
				(width 0.1)
				(type default)
			)
			(layer "F.Fab")
		)
		(fp_line
			(start 0.700024 -1.500124)
			(end 0.700024 1.500124)
			(stroke
				(width 0.1)
				(type default)
			)
			(layer "F.Fab")
		)
		(fp_line
			(start 0.700024 1.500124)
			(end -0.700024 1.500124)
			(stroke
				(width 0.1)
				(type default)
			)
			(layer "F.Fab")
		)
		(pad "1" smd rect
			(at -1.150112 -0.94996 270)
			(size 0.6604 0.9652)
			(layers "F.Cu" "F.Mask" "F.Paste")
			(net "GND")
		)
		(pad "2" smd rect
			(at -1.150112 0.94996 270)
			(size 0.6604 0.9652)
			(layers "F.Cu" "F.Mask" "F.Paste")
			(net "PWRGD_P3V3_EN_R")
		)
		(pad "3" smd rect
			(at 1.150112 0 270)
			(size 0.6604 0.9652)
			(layers "F.Cu" "F.Mask" "F.Paste")
			(net "P3V3")
		)
	)
)
